(kicad_pcb
	(version 20260206)
	(generator "pcbnew")
	(generator_version "10.0")
	(general
		(thickness 1.6)
		(legacy_teardrops no)
	)
	(paper "A4")
	(title_block
		(title "01162023_DA0F0TEBIF0_F0T_Expander_BD_F_brd_V02_OCP.brd")
		(comment 1 "Grand Teton / footprints 6295-6300 of 9728")
	)
	(layers
		(0 "F.Cu" signal "TOP")
		(4 "In1.Cu" signal "GND")
		(6 "In2.Cu" signal "VCC")
		(8 "In3.Cu" signal "VCC1")
		(10 "In4.Cu" signal "GND1")
		(12 "In5.Cu" signal "IN1")
		(14 "In6.Cu" signal "GND2")
		(16 "In7.Cu" signal "IN2")
		(18 "In8.Cu" signal "GND3")
		(20 "In9.Cu" signal "IN3")
		(22 "In10.Cu" signal "GND4")
		(24 "In11.Cu" signal "IN4")
		(26 "In12.Cu" signal "GND5")
		(28 "In13.Cu" signal "IN5")
		(30 "In14.Cu" signal "GND6")
		(32 "In15.Cu" signal "IN6")
		(34 "In16.Cu" signal "GND7")
		(2 "B.Cu" signal "BOTTOM")
		(9 "F.Adhes" user "F.Adhesive")
		(11 "B.Adhes" user "B.Adhesive")
		(13 "F.Paste" user "Package Geometry/Pastemask Top")
		(15 "B.Paste" user "Package Geometry/Pastemask Bottom")
		(5 "F.SilkS" user "Ref Des/Silkscreen Top")
		(7 "B.SilkS" user "Ref Des/Silkscreen Bottom")
		(1 "F.Mask" user "Board Geometry/Soldermask Top")
		(3 "B.Mask" user "Board Geometry/Soldermask Bottom")
		(17 "Dwgs.User" user "User.Drawings")
		(19 "Cmts.User" user "User.Comments")
		(21 "Eco1.User" user "User.Eco1")
		(23 "Eco2.User" user "User.Eco2")
		(25 "Edge.Cuts" user "Board Geometry/Outline")
		(27 "Margin" user)
		(31 "F.CrtYd" user "Package Geometry/Place Bound Top")
		(29 "B.CrtYd" user "Package Geometry/Place Bound Bottom")
		(35 "F.Fab" user "Ref Des/Assembly Top")
		(33 "B.Fab" user "Ref Des/Assembly Bottom")
	)
	(footprint ""
		(layer "F.Cu")
		(at 226.34321 -318.648588 -90)
		(property "Reference" "PL19"
			(at 0 0 270)
			(layer "F.SilkS")
			(hide yes)
			(effects
				(font
					(size 1.27 1.27)
				)
			)
		)
		(property "Value" ""
			(at 0 0 270)
			(layer "F.Fab")
			(effects
				(font
					(size 1.27 1.27)
				)
			)
		)
		(duplicate_pad_numbers_are_jumpers no)
		(fp_line
			(start -1.27 0.5842)
			(end -1.27 -0.5842)
			(stroke
				(width 0.1524)
				(type default)
			)
			(layer "F.SilkS")
		)
		(fp_line
			(start 1.27 0.5842)
			(end -1.27 0.5842)
			(stroke
				(width 0.1524)
				(type default)
			)
			(layer "F.SilkS")
		)
		(fp_line
			(start 1.27 0.5842)
			(end 1.27 -0.5842)
			(stroke
				(width 0.1524)
				(type default)
			)
			(layer "F.SilkS")
		)
		(fp_line
			(start -1.27 -0.5588)
			(end -1.27 -0.5842)
			(stroke
				(width 0.1524)
				(type default)
			)
			(layer "F.SilkS")
		)
		(fp_line
			(start -1.27 -0.5842)
			(end 1.27 -0.5842)
			(stroke
				(width 0.1524)
				(type default)
			)
			(layer "F.SilkS")
		)
		(fp_line
			(start -0.9144 0.508)
			(end -0.9144 0.406654)
			(stroke
				(width 0.1)
				(type default)
			)
			(layer "F.Fab")
		)
		(fp_line
			(start 0.9144 0.508)
			(end -0.9144 0.508)
			(stroke
				(width 0.1)
				(type default)
			)
			(layer "F.Fab")
		)
		(fp_line
			(start -1.194308 0.406654)
			(end -1.194308 -0.406654)
			(stroke
				(width 0.1)
				(type default)
			)
			(layer "F.Fab")
		)
		(fp_line
			(start -0.9144 0.406654)
			(end -1.194308 0.406654)
			(stroke
				(width 0.1)
				(type default)
			)
			(layer "F.Fab")
		)
		(fp_line
			(start 0.9144 0.4064)
			(end 0.9144 0.508)
			(stroke
				(width 0.1)
				(type default)
			)
			(layer "F.Fab")
		)
		(fp_line
			(start 1.1938 0.4064)
			(end 0.9144 0.4064)
			(stroke
				(width 0.1)
				(type default)
			)
			(layer "F.Fab")
		)
		(fp_line
			(start -1.194308 -0.406654)
			(end -0.9144 -0.406654)
			(stroke
				(width 0.1)
				(type default)
			)
			(layer "F.Fab")
		)
		(fp_line
			(start -0.9144 -0.406654)
			(end -0.9144 -0.508)
			(stroke
				(width 0.1)
				(type default)
			)
			(layer "F.Fab")
		)
		(fp_line
			(start 0.9144 -0.406654)
			(end 1.1938 -0.406654)
			(stroke
				(width 0.1)
				(type default)
			)
			(layer "F.Fab")
		)
		(fp_line
			(start 1.1938 -0.406654)
			(end 1.1938 0.4064)
			(stroke
				(width 0.1)
				(type default)
			)
			(layer "F.Fab")
		)
		(fp_line
			(start -0.9144 -0.508)
			(end 0.9144 -0.508)
			(stroke
				(width 0.1)
				(type default)
			)
			(layer "F.Fab")
		)
		(fp_line
			(start 0.9144 -0.508)
			(end 0.9144 -0.406654)
			(stroke
				(width 0.1)
				(type default)
			)
			(layer "F.Fab")
		)
		(pad "1" smd rect
			(at -0.7366 0 180)
			(size 0.7112 0.8128)
			(layers "F.Cu" "F.Mask" "F.Paste")
			(net "P12V_AUX")
		)
		(pad "2" smd rect
			(at 0.7366 0 180)
			(size 0.7112 0.8128)
			(layers "F.Cu" "F.Mask" "F.Paste")
			(net "SW_P12V_P1V25_PEX1_FLT")
		)
	)
	(footprint ""
		(layer "F.Cu")
		(at 219.164408 -29.079952 180)
		(property "Reference" "R6205"
			(at 0 0 180)
			(layer "F.SilkS")
			(hide yes)
			(effects
				(font
					(size 1.27 1.27)
				)
			)
		)
		(property "Value" ""
			(at 0 0 180)
			(layer "F.Fab")
			(effects
				(font
					(size 1.27 1.27)
				)
			)
		)
		(duplicate_pad_numbers_are_jumpers no)
		(fp_line
			(start 0.7874 0.4064)
			(end -0.7874 0.4064)
			(stroke
				(width 0.1524)
				(type default)
			)
			(layer "F.SilkS")
		)
		(fp_line
			(start 0.7874 -0.4064)
			(end 0.7874 0.4064)
			(stroke
				(width 0.1524)
				(type default)
			)
			(layer "F.SilkS")
		)
		(fp_line
			(start -0.7874 0.4064)
			(end -0.7874 -0.4064)
			(stroke
				(width 0.1524)
				(type default)
			)
			(layer "F.SilkS")
		)
		(fp_line
			(start -0.7874 -0.4064)
			(end 0.7874 -0.4064)
			(stroke
				(width 0.1524)
				(type default)
			)
			(layer "F.SilkS")
		)
		(fp_line
			(start 0.67945 0.3048)
			(end 0.120396 0.3048)
			(stroke
				(width 0.1)
				(type default)
			)
			(layer "F.Fab")
		)
		(fp_line
			(start 0.67945 -0.3048)
			(end 0.67945 0.3048)
			(stroke
				(width 0.1)
				(type default)
			)
			(layer "F.Fab")
		)
		(fp_line
			(start 0.12065 -0.2794)
			(end 0.12065 -0.3048)
			(stroke
				(width 0.1)
				(type default)
			)
			(layer "F.Fab")
		)
		(fp_line
			(start 0.12065 -0.3048)
			(end 0.67945 -0.3048)
			(stroke
				(width 0.1)
				(type default)
			)
			(layer "F.Fab")
		)
		(fp_line
			(start 0.120396 0.3048)
			(end 0.120396 0.2794)
			(stroke
				(width 0.1)
				(type default)
			)
			(layer "F.Fab")
		)
		(fp_line
			(start 0.120396 0.2794)
			(end -0.12065 0.2794)
			(stroke
				(width 0.1)
				(type default)
			)
			(layer "F.Fab")
		)
		(fp_line
			(start -0.12065 0.3048)
			(end -0.67945 0.3048)
			(stroke
				(width 0.1)
				(type default)
			)
			(layer "F.Fab")
		)
		(fp_line
			(start -0.12065 0.2794)
			(end -0.12065 0.3048)
			(stroke
				(width 0.1)
				(type default)
			)
			(layer "F.Fab")
		)
		(fp_line
			(start -0.12065 -0.2794)
			(end 0.12065 -0.2794)
			(stroke
				(width 0.1)
				(type default)
			)
			(layer "F.Fab")
		)
		(fp_line
			(start -0.12065 -0.305054)
			(end -0.12065 -0.2794)
			(stroke
				(width 0.1)
				(type default)
			)
			(layer "F.Fab")
		)
		(fp_line
			(start -0.67945 0.3048)
			(end -0.67945 -0.305054)
			(stroke
				(width 0.1)
				(type default)
			)
			(layer "F.Fab")
		)
		(fp_line
			(start -0.67945 -0.305054)
			(end -0.12065 -0.305054)
			(stroke
				(width 0.1)
				(type default)
			)
			(layer "F.Fab")
		)
		(pad "1" smd circle
			(at -0.40005 0 180)
			(size 0 0)
			(layers "F.Cu" "F.Mask" "F.Paste")
			(net "GND")
		)
		(pad "2" smd circle
			(at 0.40005 0 180)
			(size 0 0)
			(layers "F.Cu" "F.Mask" "F.Paste")
			(net "SSD7_PWRDIS_R")
		)
	)
	(footprint ""
		(layer "F.Cu")
		(at 264.539984 -77.279754 90)
		(property "Reference" "R1059"
			(at 0 0 90)
			(layer "F.SilkS")
			(hide yes)
			(effects
				(font
					(size 1.27 1.27)
				)
			)
		)
		(property "Value" ""
			(at 0 0 90)
			(layer "F.Fab")
			(effects
				(font
					(size 1.27 1.27)
				)
			)
		)
		(duplicate_pad_numbers_are_jumpers no)
		(fp_line
			(start 0.7874 -0.4064)
			(end 0.7874 0.4064)
			(stroke
				(width 0.1524)
				(type default)
			)
			(layer "F.SilkS")
		)
		(fp_line
			(start -0.7874 -0.4064)
			(end 0.7874 -0.4064)
			(stroke
				(width 0.1524)
				(type default)
			)
			(layer "F.SilkS")
		)
		(fp_line
			(start 0.7874 0.4064)
			(end -0.7874 0.4064)
			(stroke
				(width 0.1524)
				(type default)
			)
			(layer "F.SilkS")
		)
		(fp_line
			(start -0.7874 0.4064)
			(end -0.7874 -0.4064)
			(stroke
				(width 0.1524)
				(type default)
			)
			(layer "F.SilkS")
		)
		(fp_line
			(start -0.12065 -0.305054)
			(end -0.12065 -0.2794)
			(stroke
				(width 0.1)
				(type default)
			)
			(layer "F.Fab")
		)
		(fp_line
			(start -0.67945 -0.305054)
			(end -0.12065 -0.305054)
			(stroke
				(width 0.1)
				(type default)
			)
			(layer "F.Fab")
		)
		(fp_line
			(start 0.67945 -0.3048)
			(end 0.67945 0.3048)
			(stroke
				(width 0.1)
				(type default)
			)
			(layer "F.Fab")
		)
		(fp_line
			(start 0.12065 -0.3048)
			(end 0.67945 -0.3048)
			(stroke
				(width 0.1)
				(type default)
			)
			(layer "F.Fab")
		)
		(fp_line
			(start 0.12065 -0.2794)
			(end 0.12065 -0.3048)
			(stroke
				(width 0.1)
				(type default)
			)
			(layer "F.Fab")
		)
		(fp_line
			(start -0.12065 -0.2794)
			(end 0.12065 -0.2794)
			(stroke
				(width 0.1)
				(type default)
			)
			(layer "F.Fab")
		)
		(fp_line
			(start 0.120396 0.2794)
			(end -0.12065 0.2794)
			(stroke
				(width 0.1)
				(type default)
			)
			(layer "F.Fab")
		)
		(fp_line
			(start -0.12065 0.2794)
			(end -0.12065 0.3048)
			(stroke
				(width 0.1)
				(type default)
			)
			(layer "F.Fab")
		)
		(fp_line
			(start 0.67945 0.3048)
			(end 0.120396 0.3048)
			(stroke
				(width 0.1)
				(type default)
			)
			(layer "F.Fab")
		)
		(fp_line
			(start 0.120396 0.3048)
			(end 0.120396 0.2794)
			(stroke
				(width 0.1)
				(type default)
			)
			(layer "F.Fab")
		)
		(fp_line
			(start -0.12065 0.3048)
			(end -0.67945 0.3048)
			(stroke
				(width 0.1)
				(type default)
			)
			(layer "F.Fab")
		)
		(fp_line
			(start -0.67945 0.3048)
			(end -0.67945 -0.305054)
			(stroke
				(width 0.1)
				(type default)
			)
			(layer "F.Fab")
		)
		(pad "1" smd circle
			(at -0.40005 0 90)
			(size 0 0)
			(layers "F.Cu" "F.Mask" "F.Paste")
			(net "GND")
		)
		(pad "2" smd circle
			(at 0.40005 0 90)
			(size 0 0)
			(layers "F.Cu" "F.Mask" "F.Paste")
			(net "CLK_BUFFER_9ZXL0851E_8_15_OE2_N")
		)
	)
	(footprint ""
		(layer "F.Cu")
		(at 91.0336 -304.036476 90)
		(property "Reference" "R1250"
			(at 0 0 90)
			(layer "F.SilkS")
			(hide yes)
			(effects
				(font
					(size 1.27 1.27)
				)
			)
		)
		(property "Value" ""
			(at 0 0 90)
			(layer "F.Fab")
			(effects
				(font
					(size 1.27 1.27)
				)
			)
		)
		(duplicate_pad_numbers_are_jumpers no)
		(fp_line
			(start 0.7874 -0.4064)
			(end 0.7874 0.4064)
			(stroke
				(width 0.1524)
				(type default)
			)
			(layer "F.SilkS")
		)
		(fp_line
			(start -0.7874 -0.4064)
			(end 0.7874 -0.4064)
			(stroke
				(width 0.1524)
				(type default)
			)
			(layer "F.SilkS")
		)
		(fp_line
			(start 0.7874 0.4064)
			(end -0.7874 0.4064)
			(stroke
				(width 0.1524)
				(type default)
			)
			(layer "F.SilkS")
		)
		(fp_line
			(start -0.7874 0.4064)
			(end -0.7874 -0.4064)
			(stroke
				(width 0.1524)
				(type default)
			)
			(layer "F.SilkS")
		)
		(fp_line
			(start -0.12065 -0.305054)
			(end -0.12065 -0.2794)
			(stroke
				(width 0.1)
				(type default)
			)
			(layer "F.Fab")
		)
		(fp_line
			(start -0.67945 -0.305054)
			(end -0.12065 -0.305054)
			(stroke
				(width 0.1)
				(type default)
			)
			(layer "F.Fab")
		)
		(fp_line
			(start 0.67945 -0.3048)
			(end 0.67945 0.3048)
			(stroke
				(width 0.1)
				(type default)
			)
			(layer "F.Fab")
		)
		(fp_line
			(start 0.12065 -0.3048)
			(end 0.67945 -0.3048)
			(stroke
				(width 0.1)
				(type default)
			)
			(layer "F.Fab")
		)
		(fp_line
			(start 0.12065 -0.2794)
			(end 0.12065 -0.3048)
			(stroke
				(width 0.1)
				(type default)
			)
			(layer "F.Fab")
		)
		(fp_line
			(start -0.12065 -0.2794)
			(end 0.12065 -0.2794)
			(stroke
				(width 0.1)
				(type default)
			)
			(layer "F.Fab")
		)
		(fp_line
			(start 0.120396 0.2794)
			(end -0.12065 0.2794)
			(stroke
				(width 0.1)
				(type default)
			)
			(layer "F.Fab")
		)
		(fp_line
			(start -0.12065 0.2794)
			(end -0.12065 0.3048)
			(stroke
				(width 0.1)
				(type default)
			)
			(layer "F.Fab")
		)
		(fp_line
			(start 0.67945 0.3048)
			(end 0.120396 0.3048)
			(stroke
				(width 0.1)
				(type default)
			)
			(layer "F.Fab")
		)
		(fp_line
			(start 0.120396 0.3048)
			(end 0.120396 0.2794)
			(stroke
				(width 0.1)
				(type default)
			)
			(layer "F.Fab")
		)
		(fp_line
			(start -0.12065 0.3048)
			(end -0.67945 0.3048)
			(stroke
				(width 0.1)
				(type default)
			)
			(layer "F.Fab")
		)
		(fp_line
			(start -0.67945 0.3048)
			(end -0.67945 -0.305054)
			(stroke
				(width 0.1)
				(type default)
			)
			(layer "F.Fab")
		)
		(pad "1" smd circle
			(at -0.40005 0 90)
			(size 0 0)
			(layers "F.Cu" "F.Mask" "F.Paste")
			(net "GND")
		)
		(pad "2" smd circle
			(at 0.40005 0 90)
			(size 0 0)
			(layers "F.Cu" "F.Mask" "F.Paste")
			(net "PEX0_SPARE1")
		)
	)
	(footprint ""
		(layer "F.Cu")
		(at 217.235786 -217.286586 180)
		(property "Reference" "R1501"
			(at 0 0 180)
			(layer "F.SilkS")
			(hide yes)
			(effects
				(font
					(size 1.27 1.27)
				)
			)
		)
		(property "Value" ""
			(at 0 0 180)
			(layer "F.Fab")
			(effects
				(font
					(size 1.27 1.27)
				)
			)
		)
		(duplicate_pad_numbers_are_jumpers no)
		(fp_line
			(start 0.7874 0.4064)
			(end -0.7874 0.4064)
			(stroke
				(width 0.1524)
				(type default)
			)
			(layer "F.SilkS")
		)
		(fp_line
			(start 0.7874 -0.4064)
			(end 0.7874 0.4064)
			(stroke
				(width 0.1524)
				(type default)
			)
			(layer "F.SilkS")
		)
		(fp_line
			(start -0.7874 0.4064)
			(end -0.7874 -0.4064)
			(stroke
				(width 0.1524)
				(type default)
			)
			(layer "F.SilkS")
		)
		(fp_line
			(start -0.7874 -0.4064)
			(end 0.7874 -0.4064)
			(stroke
				(width 0.1524)
				(type default)
			)
			(layer "F.SilkS")
		)
		(fp_line
			(start 0.67945 0.3048)
			(end 0.120396 0.3048)
			(stroke
				(width 0.1)
				(type default)
			)
			(layer "F.Fab")
		)
		(fp_line
			(start 0.67945 -0.3048)
			(end 0.67945 0.3048)
			(stroke
				(width 0.1)
				(type default)
			)
			(layer "F.Fab")
		)
		(fp_line
			(start 0.12065 -0.2794)
			(end 0.12065 -0.3048)
			(stroke
				(width 0.1)
				(type default)
			)
			(layer "F.Fab")
		)
		(fp_line
			(start 0.12065 -0.3048)
			(end 0.67945 -0.3048)
			(stroke
				(width 0.1)
				(type default)
			)
			(layer "F.Fab")
		)
		(fp_line
			(start 0.120396 0.3048)
			(end 0.120396 0.2794)
			(stroke
				(width 0.1)
				(type default)
			)
			(layer "F.Fab")
		)
		(fp_line
			(start 0.120396 0.2794)
			(end -0.12065 0.2794)
			(stroke
				(width 0.1)
				(type default)
			)
			(layer "F.Fab")
		)
		(fp_line
			(start -0.12065 0.3048)
			(end -0.67945 0.3048)
			(stroke
				(width 0.1)
				(type default)
			)
			(layer "F.Fab")
		)
		(fp_line
			(start -0.12065 0.2794)
			(end -0.12065 0.3048)
			(stroke
				(width 0.1)
				(type default)
			)
			(layer "F.Fab")
		)
		(fp_line
			(start -0.12065 -0.2794)
			(end 0.12065 -0.2794)
			(stroke
				(width 0.1)
				(type default)
			)
			(layer "F.Fab")
		)
		(fp_line
			(start -0.12065 -0.305054)
			(end -0.12065 -0.2794)
			(stroke
				(width 0.1)
				(type default)
			)
			(layer "F.Fab")
		)
		(fp_line
			(start -0.67945 0.3048)
			(end -0.67945 -0.305054)
			(stroke
				(width 0.1)
				(type default)
			)
			(layer "F.Fab")
		)
		(fp_line
			(start -0.67945 -0.305054)
			(end -0.12065 -0.305054)
			(stroke
				(width 0.1)
				(type default)
			)
			(layer "F.Fab")
		)
		(pad "1" smd circle
			(at -0.40005 0 180)
			(size 0 0)
			(layers "F.Cu" "F.Mask" "F.Paste")
			(net "SMB_NIC5_SDA")
		)
		(pad "2" smd circle
			(at 0.40005 0 180)
			(size 0 0)
			(layers "F.Cu" "F.Mask" "F.Paste")
			(net "SMB_NIC5_R_SDA")
		)
	)
	(footprint ""
		(layer "F.Cu")
		(at 366.731296 -123.903994 -90)
		(property "Reference" "PC479"
			(at 0 0 270)
			(layer "F.SilkS")
			(hide yes)
			(effects
				(font
					(size 1.27 1.27)
				)
			)
		)
		(property "Value" ""
			(at 0 0 270)
			(layer "F.Fab")
			(effects
				(font
					(size 1.27 1.27)
				)
			)
		)
		(duplicate_pad_numbers_are_jumpers no)
		(fp_line
			(start -1.524 0.762)
			(end -1.524 -0.762)
			(stroke
				(width 0.1524)
				(type default)
			)
			(layer "F.SilkS")
		)
		(fp_line
			(start 1.524 0.762)
			(end -1.524 0.762)
			(stroke
				(width 0.1524)
				(type default)
			)
			(layer "F.SilkS")
		)
		(fp_line
			(start -1.524 -0.762)
			(end 1.524 -0.762)
			(stroke
				(width 0.1524)
				(type default)
			)
			(layer "F.SilkS")
		)
		(fp_line
			(start 1.524 -0.762)
			(end 1.524 0.762)
			(stroke
				(width 0.1524)
				(type default)
			)
			(layer "F.SilkS")
		)
		(fp_line
			(start -1.1049 0.724916)
			(end 1.1049 0.724916)
			(stroke
				(width 0.1)
				(type default)
			)
			(layer "F.Fab")
		)
		(fp_line
			(start 1.1049 0.724916)
			(end 1.1049 -0.724916)
			(stroke
				(width 0.1)
				(type default)
			)
			(layer "F.Fab")
		)
		(fp_line
			(start -1.1049 -0.724916)
			(end -1.1049 0.724916)
			(stroke
				(width 0.1)
				(type default)
			)
			(layer "F.Fab")
		)
		(fp_line
			(start 1.1049 -0.724916)
			(end -1.1049 -0.724916)
			(stroke
				(width 0.1)
				(type default)
			)
			(layer "F.Fab")
		)
		(pad "1" smd rect
			(at -0.889 0 90)
			(size 1.016 1.27)
			(layers "F.Cu" "F.Mask" "F.Paste")
			(net "P3V3_NIC6")
		)
		(pad "2" smd rect
			(at 0.889 0 90)
			(size 1.016 1.27)
			(layers "F.Cu" "F.Mask" "F.Paste")
			(net "GND")
		)
	)
)
